# T6G (Grand Teton) — schematic netlist excerpt (pin names and nets, part order shuffled) for the footprints in the layout excerpt that follows; sources: Cadence DE-HDL packaged netlist, KiCad conversion of 04192023_DAF0TMB3IC0_F0TG_MB_C_brd_V02_OCP.brd

PR211  Q_RES  0 5% CHIP  pkg 0402LF  page 215 : A = PVDDCR_SOC_P1_VOS1 ; B = PVDDCR_SOC_P1
C118  Q_CAP  10UF 6.3V 20% X6S  pkg C0402  page 323 : A = P1V8_CPU1_RT_1D ; B = GND

(kicad_pcb
	(version 20260206)
	(generator "pcbnew")
	(generator_version "10.0")
	(general
		(thickness 1.6)
		(legacy_teardrops no)
	)
	(paper "A4")
	(title_block
		(title "04192023_DAF0TMB3IC0_F0TG_MB_C_brd_V02_OCP.brd")
		(comment 1 "Grand Teton / footprints 8156-8157 of 8354")
	)
	(layers
		(0 "F.Cu" signal "TOP")
		(4 "In1.Cu" signal "GND")
		(6 "In2.Cu" signal "IN1")
		(8 "In3.Cu" signal "GND1")
		(10 "In4.Cu" signal "IN2")
		(12 "In5.Cu" signal "GND2")
		(14 "In6.Cu" signal "IN3")
		(16 "In7.Cu" signal "GND3")
		(18 "In8.Cu" signal "VCC")
		(20 "In9.Cu" signal "VCC1")
		(22 "In10.Cu" signal "GND4")
		(24 "In11.Cu" signal "IN4")
		(26 "In12.Cu" signal "GND5")
		(28 "In13.Cu" signal "IN5")
		(30 "In14.Cu" signal "GND6")
		(32 "In15.Cu" signal "IN6")
		(34 "In16.Cu" signal "GND7")
		(2 "B.Cu" signal "BOTTOM")
		(9 "F.Adhes" user "F.Adhesive")
		(11 "B.Adhes" user "B.Adhesive")
		(13 "F.Paste" user "Package Geometry/Pastemask Top")
		(15 "B.Paste" user "Package Geometry/Pastemask Bottom")
		(5 "F.SilkS" user "Ref Des/Silkscreen Top")
		(7 "B.SilkS" user "Ref Des/Silkscreen Bottom")
		(1 "F.Mask" user "Board Geometry/Soldermask Top")
		(3 "B.Mask" user "Board Geometry/Soldermask Bottom")
		(17 "Dwgs.User" user "User.Drawings")
		(19 "Cmts.User" user "User.Comments")
		(21 "Eco1.User" user "User.Eco1")
		(23 "Eco2.User" user "User.Eco2")
		(25 "Edge.Cuts" user "Board Geometry/Outline")
		(27 "Margin" user)
		(31 "F.CrtYd" user "Package Geometry/Place Bound Top")
		(29 "B.CrtYd" user "Package Geometry/Place Bound Bottom")
		(35 "F.Fab" user "Ref Des/Assembly Top")
		(33 "B.Fab" user "Ref Des/Assembly Bottom")
	)
	(footprint ""
		(layer "B.Cu")
		(at 73.068434 -386.745988 -90)
		(property "Reference" "C118"
			(at 0 0 90)
			(layer "B.SilkS")
			(hide yes)
			(effects
				(font
					(size 1.27 1.27)
				)
				(justify mirror)
			)
		)
		(property "Value" ""
			(at 0 0 90)
			(layer "B.Fab")
			(effects
				(font
					(size 1.27 1.27)
				)
				(justify mirror)
			)
		)
		(duplicate_pad_numbers_are_jumpers no)
		(fp_line
			(start -0.7874 0.4064)
			(end 0.7874 0.4064)
			(stroke
				(width 0.1524)
				(type default)
			)
			(layer "B.SilkS")
		)
		(fp_line
			(start 0.7874 0.4064)
			(end 0.7874 -0.4064)
			(stroke
				(width 0.1524)
				(type default)
			)
			(layer "B.SilkS")
		)
		(fp_line
			(start -0.7874 -0.4064)
			(end -0.7874 0.4064)
			(stroke
				(width 0.1524)
				(type default)
			)
			(layer "B.SilkS")
		)
		(fp_line
			(start 0.7874 -0.4064)
			(end -0.7874 -0.4064)
			(stroke
				(width 0.1524)
				(type default)
			)
			(layer "B.SilkS")
		)
		(fp_line
			(start -0.67945 0.3048)
			(end -0.120396 0.3048)
			(stroke
				(width 0.1)
				(type default)
			)
			(layer "B.Fab")
		)
		(fp_line
			(start -0.120396 0.3048)
			(end -0.120396 0.2794)
			(stroke
				(width 0.1)
				(type default)
			)
			(layer "B.Fab")
		)
		(fp_line
			(start 0.12065 0.3048)
			(end 0.67945 0.3048)
			(stroke
				(width 0.1)
				(type default)
			)
			(layer "B.Fab")
		)
		(fp_line
			(start 0.67945 0.3048)
			(end 0.67945 -0.305054)
			(stroke
				(width 0.1)
				(type default)
			)
			(layer "B.Fab")
		)
		(fp_line
			(start -0.120396 0.2794)
			(end 0.12065 0.2794)
			(stroke
				(width 0.1)
				(type default)
			)
			(layer "B.Fab")
		)
		(fp_line
			(start 0.12065 0.2794)
			(end 0.12065 0.3048)
			(stroke
				(width 0.1)
				(type default)
			)
			(layer "B.Fab")
		)
		(fp_line
			(start -0.12065 -0.2794)
			(end -0.12065 -0.3048)
			(stroke
				(width 0.1)
				(type default)
			)
			(layer "B.Fab")
		)
		(fp_line
			(start 0.12065 -0.2794)
			(end -0.12065 -0.2794)
			(stroke
				(width 0.1)
				(type default)
			)
			(layer "B.Fab")
		)
		(fp_line
			(start -0.67945 -0.3048)
			(end -0.67945 0.3048)
			(stroke
				(width 0.1)
				(type default)
			)
			(layer "B.Fab")
		)
		(fp_line
			(start -0.12065 -0.3048)
			(end -0.67945 -0.3048)
			(stroke
				(width 0.1)
				(type default)
			)
			(layer "B.Fab")
		)
		(fp_line
			(start 0.12065 -0.305054)
			(end 0.12065 -0.2794)
			(stroke
				(width 0.1)
				(type default)
			)
			(layer "B.Fab")
		)
		(fp_line
			(start 0.67945 -0.305054)
			(end 0.12065 -0.305054)
			(stroke
				(width 0.1)
				(type default)
			)
			(layer "B.Fab")
		)
		(pad "1" smd circle
			(at 0.40005 0 90)
			(size 0 0)
			(layers "B.Cu" "B.Mask" "B.Paste")
			(net "P1V8_CPU1_RT_1D")
		)
		(pad "2" smd circle
			(at -0.40005 0 90)
			(size 0 0)
			(layers "B.Cu" "B.Mask" "B.Paste")
			(net "GND")
		)
	)
	(footprint ""
		(layer "B.Cu")
		(at 119.34698 -169.258234 90)
		(property "Reference" "PR211"
			(at 0 0 90)
			(layer "B.SilkS")
			(hide yes)
			(effects
				(font
					(size 1.27 1.27)
				)
				(justify mirror)
			)
		)
		(property "Value" ""
			(at 0 0 90)
			(layer "B.Fab")
			(effects
				(font
					(size 1.27 1.27)
				)
				(justify mirror)
			)
		)
		(duplicate_pad_numbers_are_jumpers no)
		(fp_line
			(start 0.7874 -0.4064)
			(end -0.7874 -0.4064)
			(stroke
				(width 0.1524)
				(type default)
			)
			(layer "B.SilkS")
		)
		(fp_line
			(start -0.7874 -0.4064)
			(end -0.7874 0.4064)
			(stroke
				(width 0.1524)
				(type default)
			)
			(layer "B.SilkS")
		)
		(fp_line
			(start 0.7874 0.4064)
			(end 0.7874 -0.4064)
			(stroke
				(width 0.1524)
				(type default)
			)
			(layer "B.SilkS")
		)
		(fp_line
			(start -0.7874 0.4064)
			(end 0.7874 0.4064)
			(stroke
				(width 0.1524)
				(type default)
			)
			(layer "B.SilkS")
		)
		(fp_line
			(start 0.67945 -0.305054)
			(end 0.12065 -0.305054)
			(stroke
				(width 0.1)
				(type default)
			)
			(layer "B.Fab")
		)
		(fp_line
			(start 0.12065 -0.305054)
			(end 0.12065 -0.2794)
			(stroke
				(width 0.1)
				(type default)
			)
			(layer "B.Fab")
		)
		(fp_line
			(start -0.12065 -0.3048)
			(end -0.67945 -0.3048)
			(stroke
				(width 0.1)
				(type default)
			)
			(layer "B.Fab")
		)
		(fp_line
			(start -0.67945 -0.3048)
			(end -0.67945 0.3048)
			(stroke
				(width 0.1)
				(type default)
			)
			(layer "B.Fab")
		)
		(fp_line
			(start 0.12065 -0.2794)
			(end -0.12065 -0.2794)
			(stroke
				(width 0.1)
				(type default)
			)
			(layer "B.Fab")
		)
		(fp_line
			(start -0.12065 -0.2794)
			(end -0.12065 -0.3048)
			(stroke
				(width 0.1)
				(type default)
			)
			(layer "B.Fab")
		)
		(fp_line
			(start 0.12065 0.2794)
			(end 0.12065 0.3048)
			(stroke
				(width 0.1)
				(type default)
			)
			(layer "B.Fab")
		)
		(fp_line
			(start -0.120396 0.2794)
			(end 0.12065 0.2794)
			(stroke
				(width 0.1)
				(type default)
			)
			(layer "B.Fab")
		)
		(fp_line
			(start 0.67945 0.3048)
			(end 0.67945 -0.305054)
			(stroke
				(width 0.1)
				(type default)
			)
			(layer "B.Fab")
		)
		(fp_line
			(start 0.12065 0.3048)
			(end 0.67945 0.3048)
			(stroke
				(width 0.1)
				(type default)
			)
			(layer "B.Fab")
		)
		(fp_line
			(start -0.120396 0.3048)
			(end -0.120396 0.2794)
			(stroke
				(width 0.1)
				(type default)
			)
			(layer "B.Fab")
		)
		(fp_line
			(start -0.67945 0.3048)
			(end -0.120396 0.3048)
			(stroke
				(width 0.1)
				(type default)
			)
			(layer "B.Fab")
		)
		(pad "1" smd circle
			(at 0.40005 0 270)
			(size 0 0)
			(layers "B.Cu" "B.Mask" "B.Paste")
			(net "PVDDCR_SOC_P1_VOS1")
		)
		(pad "2" smd circle
			(at -0.40005 0 270)
			(size 0 0)
			(layers "B.Cu" "B.Mask" "B.Paste")
			(net "PVDDCR_SOC_P1")
		)
	)
)
